FILE_TYPE=LIBRARY_PARTS;
primitive 'ICS9FGP204','ICS9FGP204_MLFP';
  pin
    'VDD32K':
      PIN_NUMBER='(12)';
      PINUSE='POWER';
      NO_LOAD_CHECK='Both';
      NO_IO_CHECK='Both';
      NO_ASSERT_CHECK='TRUE';
      NO_DIR_CHECK='TRUE';
      ALLOW_CONNECT='TRUE';
    '32KHZ':
      PIN_NUMBER='(13)';
      OUTPUT_LOAD='(1.0,-1.0)';
    'GND32K':
      PIN_NUMBER='(14)';
      PINUSE='GROUND';
      NO_LOAD_CHECK='Both';
      NO_IO_CHECK='Both';
      NO_ASSERT_CHECK='TRUE';
      NO_DIR_CHECK='TRUE';
      ALLOW_CONNECT='TRUE';
    '25MHZ_0':
      PIN_NUMBER='(16)';
      OUTPUT_LOAD='(1.0,-1.0)';
    '25MHZ_1':
      PIN_NUMBER='(17)';
      OUTPUT_LOAD='(1.0,-1.0)';
    'RMII'<1>:
      PIN_NUMBER='(32)';
      OUTPUT_LOAD='(1.0,-1.0)';
    'RMII'<2>:
      PIN_NUMBER='(29)';
      OUTPUT_LOAD='(1.0,-1.0)';
    'RMII'<5>:
      PIN_NUMBER='(24)';
      OUTPUT_LOAD='(1.0,-1.0)';
    'RMII'<4>:
      PIN_NUMBER='(25)';
      OUTPUT_LOAD='(1.0,-1.0)';
    'RMII'<3>:
      PIN_NUMBER='(28)';
      OUTPUT_LOAD='(1.0,-1.0)';
    'RMII'<0>:
      PIN_NUMBER='(33)';
      OUTPUT_LOAD='(1.0,-1.0)';
    'GND'<1>:
      PIN_NUMBER='(41)';
      PINUSE='GROUND';
      NO_LOAD_CHECK='Both';
      NO_IO_CHECK='Both';
      NO_ASSERT_CHECK='TRUE';
      NO_DIR_CHECK='TRUE';
      ALLOW_CONNECT='TRUE';
    'GND33':
      PIN_NUMBER='(21)';
      PINUSE='GROUND';
      NO_LOAD_CHECK='Both';
      NO_IO_CHECK='Both';
      NO_ASSERT_CHECK='TRUE';
      NO_DIR_CHECK='TRUE';
      ALLOW_CONNECT='TRUE';
    'GND'<0>:
      PIN_NUMBER='(1)';
      PINUSE='GROUND';
      NO_LOAD_CHECK='Both';
      NO_IO_CHECK='Both';
      NO_ASSERT_CHECK='TRUE';
      NO_DIR_CHECK='TRUE';
      ALLOW_CONNECT='TRUE';
    'DOT96SSC':
      PIN_NUMBER='(4)';
      OUTPUT_LOAD='(1.0,-1.0)';
    'DOT96SST':
      PIN_NUMBER='(3)';
      OUTPUT_LOAD='(1.0,-1.0)';
    'CPUCLKC0':
      PIN_NUMBER='(8)';
      OUTPUT_LOAD='(1.0,-1.0)';
    'GNDREF':
      PIN_NUMBER='(18)';
      PINUSE='GROUND';
      NO_LOAD_CHECK='Both';
      NO_IO_CHECK='Both';
      NO_ASSERT_CHECK='TRUE';
      NO_DIR_CHECK='TRUE';
      ALLOW_CONNECT='TRUE';
    'CPUCLKT0':
      PIN_NUMBER='(7)';
      OUTPUT_LOAD='(1.0,-1.0)';
    'VDDREF':
      PIN_NUMBER='(15)';
      PINUSE='POWER';
      NO_LOAD_CHECK='Both';
      NO_IO_CHECK='Both';
      NO_ASSERT_CHECK='TRUE';
      NO_DIR_CHECK='TRUE';
      ALLOW_CONNECT='TRUE';
    'IREF':
      PIN_NUMBER='(11)';
      OUTPUT_LOAD='(1.0,-1.0)';
    'X1_25':
      PIN_NUMBER='(19)';
      INPUT_LOAD='(-0.01,0.01)';
    'GNDRMII'<0>:
      PIN_NUMBER='(27)';
      PINUSE='GROUND';
      NO_LOAD_CHECK='Both';
      NO_IO_CHECK='Both';
      NO_ASSERT_CHECK='TRUE';
      NO_DIR_CHECK='TRUE';
      ALLOW_CONNECT='TRUE';
    'VDDRMII'<0>:
      PIN_NUMBER='(26)';
      PINUSE='POWER';
      NO_LOAD_CHECK='Both';
      NO_IO_CHECK='Both';
      NO_ASSERT_CHECK='TRUE';
      NO_DIR_CHECK='TRUE';
      ALLOW_CONNECT='TRUE';
    'VDDRMII'<1>:
      PIN_NUMBER='(31)';
      PINUSE='POWER';
      NO_LOAD_CHECK='Both';
      NO_IO_CHECK='Both';
      NO_ASSERT_CHECK='TRUE';
      NO_DIR_CHECK='TRUE';
      ALLOW_CONNECT='TRUE';
    'GNDRMII'<1>:
      PIN_NUMBER='(30)';
      PINUSE='GROUND';
      NO_LOAD_CHECK='Both';
      NO_IO_CHECK='Both';
      NO_ASSERT_CHECK='TRUE';
      NO_DIR_CHECK='TRUE';
      ALLOW_CONNECT='TRUE';
    '33MHZ_SMBADR':
      PIN_NUMBER='(22)';
      BIDIRECTIONAL='TRUE';
      INPUT_LOAD='(-0.01,0.01)';
      OUTPUT_LOAD='(1.0,-1.0)';
    'VDD33':
      PIN_NUMBER='(23)';
      PINUSE='POWER';
      NO_LOAD_CHECK='Both';
      NO_IO_CHECK='Both';
      NO_ASSERT_CHECK='TRUE';
      NO_DIR_CHECK='TRUE';
      ALLOW_CONNECT='TRUE';
    'OE_96':
      PIN_NUMBER='(5)';
      INPUT_LOAD='(-0.01,0.01)';
    'VDD96':
      PIN_NUMBER='(2)';
      PINUSE='POWER';
      NO_LOAD_CHECK='Both';
      NO_IO_CHECK='Both';
      NO_ASSERT_CHECK='TRUE';
      NO_DIR_CHECK='TRUE';
      ALLOW_CONNECT='TRUE';
    'OE_CPU':
      PIN_NUMBER='(6)';
      INPUT_LOAD='(-0.01,0.01)';
    'GNDCPU':
      PIN_NUMBER='(10)';
      PINUSE='GROUND';
      NO_LOAD_CHECK='Both';
      NO_IO_CHECK='Both';
      NO_ASSERT_CHECK='TRUE';
      NO_DIR_CHECK='TRUE';
      ALLOW_CONNECT='TRUE';
    'VDDCPU':
      PIN_NUMBER='(9)';
      PINUSE='POWER';
      NO_LOAD_CHECK='Both';
      NO_IO_CHECK='Both';
      NO_ASSERT_CHECK='TRUE';
      NO_DIR_CHECK='TRUE';
      ALLOW_CONNECT='TRUE';
    'VTTPWR_GD_PD_N':
      PIN_NUMBER='(40)';
      INPUT_LOAD='(-0.01,0.01)';
    'SMBCLK':
      PIN_NUMBER='(38)';
      INPUT_LOAD='(-0.01,0.01)';
    'X2_25':
      PIN_NUMBER='(20)';
      OUTPUT_LOAD='(1.0,-1.0)';
    'SMBDAT':
      PIN_NUMBER='(39)';
      BIDIRECTIONAL='TRUE';
      INPUT_LOAD='(-0.01,0.01)';
      OUTPUT_LOAD='(1.0,-1.0)';
    'VDD_RGMII':
      PIN_NUMBER='(34)';
      INPUT_LOAD='(-0.01,0.01)';
    'GND_RGMII':
      PIN_NUMBER='(35)';
      PINUSE='GROUND';
      NO_LOAD_CHECK='Both';
      NO_IO_CHECK='Both';
      NO_ASSERT_CHECK='TRUE';
      NO_DIR_CHECK='TRUE';
      ALLOW_CONNECT='TRUE';
    'RGMII'<0>:
      PIN_NUMBER='(37)';
      OUTPUT_LOAD='(1.0,-1.0)';
    'RGMII'<1>:
      PIN_NUMBER='(36)';
      OUTPUT_LOAD='(1.0,-1.0)';
  end_pin;
  body
    PART_NAME='ICS9FGP204';
    BODY_NAME='ICS9FGP204';
    PHYS_DES_PREFIX='EU';
  end_body;
end_primitive;

END.
